FILE_TYPE = CONNECTIVITY;
{Allegro Design Entry HDL 16.6-p007 (v16-6-112F) 10/10/2012}
"PAGE_NUMBER" = 24;
0"NC";
1"M_B_DQS_DP<17:0>";
2"M_B_MA<17:0>";
3"M_B_DQS_DN<17:0>";
4"M_B_ODT<3:0>";
5"M_B_CS_N<7:0>";
6"M_B_CKE<3:0>";
7"M_B_BG<1:0>";
8"M_B_BA<1:0>";
9"M_B_DQ<63:0>";
10"M_B_ECC<7:0>";
11"M_B_CLK_DP<3:0>";
12"M_B_CLK_DN<3:0>";
13"M_B_DQS_DN<8>";
14"M_B_DQ<55>";
15"M_B_DQ<41>";
16"M_B_DQS_DP<2>";
17"M_B_DQ<28>";
18"M_B_DQ<53>";
19"M_B_ODT<3>";
20"M_B_DQ<35>";
21"M_B_DQ<33>";
22"M_B_DQ<38>";
23"M_B_DQ<29>";
24"M_B_DQ<5>";
25"M_B_C<2>";
26"M_B_CLK_DN<3>";
27"M_B_CLK_DN<2>";
28"M_B_CLK_DN<1>";
29"M_B_CLK_DN<0>";
30"M_B_CLK_DP<3>";
31"M_B_CLK_DP<2>";
32"M_B_CLK_DP<1>";
33"M_B_CLK_DP<0>";
34"M_B_DQ<10>";
35"M_B_DQ<9>";
36"M_B_DQ<8>";
37"M_B_DQ<7>";
38"M_B_DQ<6>";
39"M_B_DQ<4>";
40"M_B_DQ<3>";
41"M_B_DQ<2>";
42"M_B_DQ<1>";
43"M_B_DQ<0>";
44"M_B_ECC<7>";
45"M_B_ECC<6>";
46"M_B_ECC<5>";
47"M_B_ECC<4>";
48"M_B_ECC<3>";
49"M_B_ECC<2>";
50"M_B_ECC<1>";
51"M_B_ECC<0>";
52"M_B_DQ<51>";
53"M_B_DQ<50>";
54"M_B_DQ<49>";
55"M_B_DQ<48>";
56"M_B_DQ<47>";
57"M_B_DQ<46>";
58"M_B_DQ<45>";
59"M_B_DQ<44>";
60"M_B_DQ<43>";
61"M_B_DQ<42>";
62"M_B_DQ<40>";
63"M_B_DQ<39>";
64"M_B_DQ<37>";
65"M_B_DQ<36>";
66"M_B_DQ<34>";
67"M_B_DQ<32>";
68"M_B_DQ<31>";
69"M_B_DQ<30>";
70"M_B_DQ<27>";
71"M_B_DQ<26>";
72"M_B_DQ<25>";
73"M_B_DQ<24>";
74"M_B_DQ<23>";
75"M_B_DQ<22>";
76"M_B_DQ<21>";
77"M_B_DQ<20>";
78"M_B_DQ<19>";
79"M_B_DQ<18>";
80"M_B_DQ<17>";
81"M_B_DQ<16>";
82"M_B_DQ<15>";
83"M_B_DQ<14>";
84"M_B_DQ<13>";
85"M_B_DQ<12>";
86"M_B_DQ<11>";
87"M_B_DQ<63>";
88"M_B_DQ<62>";
89"M_B_DQ<61>";
90"M_B_DQ<60>";
91"M_B_DQ<59>";
92"M_B_DQ<58>";
93"M_B_DQ<57>";
94"M_B_DQ<56>";
95"M_B_DQ<54>";
96"M_B_DQ<52>";
97"M_B_BA<1>";
98"M_B_BA<0>";
99"M_B_BG<1>";
100"M_B_BG<0>";
101"M_B_CKE<3>";
102"M_B_CKE<2>";
103"M_B_CKE<1>";
104"M_B_CKE<0>";
105"M_B_CS_N<7>";
106"M_B_CS_N<6>";
107"M_B_CS_N<5>";
108"M_B_CS_N<4>";
109"M_B_CS_N<3>";
110"M_B_CS_N<2>";
111"M_B_CS_N<1>";
112"M_B_CS_N<0>";
113"M_B_MA<2>";
114"M_B_MA<1>";
115"M_B_MA<0>";
116"M_B_ODT<2>";
117"M_B_ODT<1>";
118"M_B_ODT<0>";
119"M_B_DQS_DN<17>";
120"M_B_DQS_DN<16>";
121"M_B_DQS_DN<15>";
122"M_B_DQS_DN<14>";
123"M_B_DQS_DN<13>";
124"M_B_DQS_DN<12>";
125"M_B_DQS_DN<11>";
126"M_B_DQS_DN<10>";
127"M_B_DQS_DN<9>";
128"M_B_DQS_DN<7>";
129"M_B_DQS_DN<6>";
130"M_B_DQS_DN<5>";
131"M_B_DQS_DN<4>";
132"M_B_DQS_DN<3>";
133"M_B_DQS_DN<2>";
134"M_B_DQS_DN<1>";
135"M_B_DQS_DN<0>";
136"M_B_DQS_DP<5>";
137"M_B_DQS_DP<4>";
138"M_B_DQS_DP<3>";
139"M_B_DQS_DP<1>";
140"M_B_DQS_DP<0>";
141"M_B_MA<17>";
142"M_B_MA<16>";
143"M_B_MA<15>";
144"M_B_MA<14>";
145"M_B_MA<13>";
146"M_B_MA<12>";
147"M_B_MA<11>";
148"M_B_MA<10>";
149"M_B_MA<9>";
150"M_B_MA<8>";
151"M_B_MA<7>";
152"M_B_MA<6>";
153"M_B_MA<5>";
154"M_B_MA<4>";
155"M_B_MA<3>";
156"M_B_PAR";
157"M_B_ALERT_N";
158"M_B_ACT_N";
159"M_B_DQS_DP<17>";
160"M_B_DQS_DP<16>";
161"M_B_DQS_DP<15>";
162"M_B_DQS_DP<14>";
163"M_B_DQS_DP<13>";
164"M_B_DQS_DP<12>";
165"M_B_DQS_DP<11>";
166"M_B_DQS_DP<10>";
167"M_B_DQS_DP<9>";
168"M_B_DQS_DP<8>";
169"M_B_DQS_DP<7>";
170"M_B_DQS_DP<6>";
%"TAP"
"6","(-5525,750)","0","mstr_standard","I10";
;
HDL_TAP"TRUE"
BODY_TYPE"PLUMBING"
CDS_LIB"mstr_standard";
"B \NAC \NWC"12;
"S \NAC"
BN"3"26;
%"TAP"
"6","(-2800,1550)","2","mstr_standard","I100";
;
HDL_TAP"TRUE"
BODY_TYPE"PLUMBING"
CDS_LIB"mstr_standard";
"B \NAC \NWC"4;
"S \NAC"
BN"3"19;
%"TAP"
"6","(-2800,1450)","2","mstr_standard","I101";
;
HDL_TAP"TRUE"
BODY_TYPE"PLUMBING"
CDS_LIB"mstr_standard";
"B \NAC \NWC"4;
"S \NAC"
BN"1"117;
%"TAP"
"6","(-2800,1650)","2","mstr_standard","I102";
;
HDL_TAP"TRUE"
BODY_TYPE"PLUMBING"
CDS_LIB"mstr_standard";
"B \NAC \NWC"6;
"S \NAC"
BN"0"104;
%"TAP"
"6","(-2800,1500)","2","mstr_standard","I103";
;
HDL_TAP"TRUE"
BODY_TYPE"PLUMBING"
CDS_LIB"mstr_standard";
"B \NAC \NWC"4;
"S \NAC"
BN"2"116;
%"TAP"
"6","(-2800,1750)","2","mstr_standard","I104";
;
HDL_TAP"TRUE"
BODY_TYPE"PLUMBING"
CDS_LIB"mstr_standard";
"B \NAC \NWC"6;
"S \NAC"
BN"2"102;
%"TAP"
"6","(-2800,1700)","2","mstr_standard","I105";
;
HDL_TAP"TRUE"
BODY_TYPE"PLUMBING"
CDS_LIB"mstr_standard";
"B \NAC \NWC"6;
"S \NAC"
BN"1"103;
%"TAP"
"6","(-2800,1900)","2","mstr_standard","I106";
;
HDL_TAP"TRUE"
BODY_TYPE"PLUMBING"
CDS_LIB"mstr_standard";
"B \NAC \NWC"2;
"S \NAC"
BN"0"115;
%"TAP"
"6","(-2800,1800)","2","mstr_standard","I107";
;
HDL_TAP"TRUE"
BODY_TYPE"PLUMBING"
CDS_LIB"mstr_standard";
"B \NAC \NWC"6;
"S \NAC"
BN"3"101;
%"TAP"
"6","(-2800,2100)","2","mstr_standard","I108";
;
HDL_TAP"TRUE"
BODY_TYPE"PLUMBING"
CDS_LIB"mstr_standard";
"B \NAC \NWC"2;
"S \NAC"
BN"4"154;
%"TAP"
"6","(-2800,2150)","2","mstr_standard","I109";
;
HDL_TAP"TRUE"
BODY_TYPE"PLUMBING"
CDS_LIB"mstr_standard";
"B \NAC \NWC"2;
"S \NAC"
BN"5"153;
%"TAP"
"6","(-5525,900)","0","mstr_standard","I11";
;
HDL_TAP"TRUE"
BODY_TYPE"PLUMBING"
CDS_LIB"mstr_standard";
"B \NAC \NWC"11;
"S \NAC"
BN"2"31;
%"TAP"
"6","(-2800,2000)","2","mstr_standard","I110";
;
HDL_TAP"TRUE"
BODY_TYPE"PLUMBING"
CDS_LIB"mstr_standard";
"B \NAC \NWC"2;
"S \NAC"
BN"2"113;
%"TAP"
"6","(-2800,2050)","2","mstr_standard","I111";
;
HDL_TAP"TRUE"
BODY_TYPE"PLUMBING"
CDS_LIB"mstr_standard";
"B \NAC \NWC"2;
"S \NAC"
BN"3"155;
%"TAP"
"6","(-2800,1950)","2","mstr_standard","I112";
;
HDL_TAP"TRUE"
BODY_TYPE"PLUMBING"
CDS_LIB"mstr_standard";
"B \NAC \NWC"2;
"S \NAC"
BN"1"114;
%"TAP"
"6","(-2800,2400)","2","mstr_standard","I113";
;
HDL_TAP"TRUE"
BODY_TYPE"PLUMBING"
CDS_LIB"mstr_standard";
"B \NAC \NWC"2;
"S \NAC"
BN"10"148;
%"TAP"
"6","(-2800,2350)","2","mstr_standard","I114";
;
HDL_TAP"TRUE"
BODY_TYPE"PLUMBING"
CDS_LIB"mstr_standard";
"B \NAC \NWC"2;
"S \NAC"
BN"9"149;
%"TAP"
"6","(-2800,2300)","2","mstr_standard","I115";
;
HDL_TAP"TRUE"
BODY_TYPE"PLUMBING"
CDS_LIB"mstr_standard";
"B \NAC \NWC"2;
"S \NAC"
BN"8"150;
%"TAP"
"6","(-2800,2250)","2","mstr_standard","I116";
;
HDL_TAP"TRUE"
BODY_TYPE"PLUMBING"
CDS_LIB"mstr_standard";
"B \NAC \NWC"2;
"S \NAC"
BN"7"151;
%"TAP"
"6","(-2800,2200)","2","mstr_standard","I117";
;
HDL_TAP"TRUE"
BODY_TYPE"PLUMBING"
CDS_LIB"mstr_standard";
"B \NAC \NWC"2;
"S \NAC"
BN"6"152;
%"TAP"
"6","(-2800,2650)","2","mstr_standard","I118";
;
HDL_TAP"TRUE"
BODY_TYPE"PLUMBING"
CDS_LIB"mstr_standard";
"B \NAC \NWC"2;
"S \NAC"
BN"15"143;
%"TAP"
"6","(-2800,2600)","2","mstr_standard","I119";
;
HDL_TAP"TRUE"
BODY_TYPE"PLUMBING"
CDS_LIB"mstr_standard";
"B \NAC \NWC"2;
"S \NAC"
BN"14"144;
%"TAP"
"6","(-5525,950)","0","mstr_standard","I12";
;
HDL_TAP"TRUE"
BODY_TYPE"PLUMBING"
CDS_LIB"mstr_standard";
"B \NAC \NWC"11;
"S \NAC"
BN"3"30;
%"TAP"
"6","(-2800,2550)","2","mstr_standard","I120";
;
HDL_TAP"TRUE"
BODY_TYPE"PLUMBING"
CDS_LIB"mstr_standard";
"B \NAC \NWC"2;
"S \NAC"
BN"13"145;
%"TAP"
"6","(-2800,2500)","2","mstr_standard","I121";
;
HDL_TAP"TRUE"
BODY_TYPE"PLUMBING"
CDS_LIB"mstr_standard";
"B \NAC \NWC"2;
"S \NAC"
BN"12"146;
%"TAP"
"6","(-2800,2450)","2","mstr_standard","I122";
;
HDL_TAP"TRUE"
BODY_TYPE"PLUMBING"
CDS_LIB"mstr_standard";
"B \NAC \NWC"2;
"S \NAC"
BN"11"147;
%"TAP"
"6","(-2800,2850)","2","mstr_standard","I123";
;
HDL_TAP"TRUE"
BODY_TYPE"PLUMBING"
CDS_LIB"mstr_standard";
"B \NAC \NWC"3;
"S \NAC"
BN"0"135;
%"TAP"
"6","(-2800,2900)","2","mstr_standard","I124";
;
HDL_TAP"TRUE"
BODY_TYPE"PLUMBING"
CDS_LIB"mstr_standard";
"B \NAC \NWC"3;
"S \NAC"
BN"1"134;
%"TAP"
"6","(-2800,2750)","2","mstr_standard","I125";
;
HDL_TAP"TRUE"
BODY_TYPE"PLUMBING"
CDS_LIB"mstr_standard";
"B \NAC \NWC"2;
"S \NAC"
BN"17"141;
%"TAP"
"6","(-2800,2700)","2","mstr_standard","I126";
;
HDL_TAP"TRUE"
BODY_TYPE"PLUMBING"
CDS_LIB"mstr_standard";
"B \NAC \NWC"2;
"S \NAC"
BN"16"142;
%"TAP"
"6","(-2800,2950)","2","mstr_standard","I127";
;
HDL_TAP"TRUE"
BODY_TYPE"PLUMBING"
CDS_LIB"mstr_standard";
"B \NAC \NWC"3;
"S \NAC"
BN"2"133;
%"TAP"
"6","(-2800,3000)","2","mstr_standard","I128";
;
HDL_TAP"TRUE"
BODY_TYPE"PLUMBING"
CDS_LIB"mstr_standard";
"B \NAC \NWC"3;
"S \NAC"
BN"3"132;
%"TAP"
"6","(-2800,3050)","2","mstr_standard","I129";
;
HDL_TAP"TRUE"
BODY_TYPE"PLUMBING"
CDS_LIB"mstr_standard";
"B \NAC \NWC"3;
"S \NAC"
BN"4"131;
%"TAP"
"6","(-5525,1050)","0","mstr_standard","I13";
;
HDL_TAP"TRUE"
BODY_TYPE"PLUMBING"
CDS_LIB"mstr_standard";
"B \NAC \NWC"10;
"S \NAC"
BN"0"51;
%"TAP"
"6","(-2800,3150)","2","mstr_standard","I130";
;
HDL_TAP"TRUE"
BODY_TYPE"PLUMBING"
CDS_LIB"mstr_standard";
"B \NAC \NWC"3;
"S \NAC"
BN"6"129;
%"TAP"
"6","(-2800,3200)","2","mstr_standard","I131";
;
HDL_TAP"TRUE"
BODY_TYPE"PLUMBING"
CDS_LIB"mstr_standard";
"B \NAC \NWC"3;
"S \NAC"
BN"7"128;
%"TAP"
"6","(-2800,3100)","2","mstr_standard","I132";
;
HDL_TAP"TRUE"
BODY_TYPE"PLUMBING"
CDS_LIB"mstr_standard";
"B \NAC \NWC"3;
"S \NAC"
BN"5"130;
%"TAP"
"6","(-2800,3250)","2","mstr_standard","I133";
;
HDL_TAP"TRUE"
BODY_TYPE"PLUMBING"
CDS_LIB"mstr_standard";
"B \NAC \NWC"3;
"S \NAC"
BN"8"13;
%"TAP"
"6","(-2800,3450)","2","mstr_standard","I134";
;
HDL_TAP"TRUE"
BODY_TYPE"PLUMBING"
CDS_LIB"mstr_standard";
"B \NAC \NWC"3;
"S \NAC"
BN"12"124;
%"TAP"
"6","(-2800,3400)","2","mstr_standard","I135";
;
HDL_TAP"TRUE"
BODY_TYPE"PLUMBING"
CDS_LIB"mstr_standard";
"B \NAC \NWC"3;
"S \NAC"
BN"11"125;
%"TAP"
"6","(-2800,3300)","2","mstr_standard","I136";
;
HDL_TAP"TRUE"
BODY_TYPE"PLUMBING"
CDS_LIB"mstr_standard";
"B \NAC \NWC"3;
"S \NAC"
BN"9"127;
%"TAP"
"6","(-2800,3350)","2","mstr_standard","I137";
;
HDL_TAP"TRUE"
BODY_TYPE"PLUMBING"
CDS_LIB"mstr_standard";
"B \NAC \NWC"3;
"S \NAC"
BN"10"126;
%"TAP"
"6","(-2800,3500)","2","mstr_standard","I138";
;
HDL_TAP"TRUE"
BODY_TYPE"PLUMBING"
CDS_LIB"mstr_standard";
"B \NAC \NWC"3;
"S \NAC"
BN"13"123;
%"TAP"
"6","(-2800,3700)","2","mstr_standard","I139";
;
HDL_TAP"TRUE"
BODY_TYPE"PLUMBING"
CDS_LIB"mstr_standard";
"B \NAC \NWC"3;
"S \NAC"
BN"17"119;
%"TAP"
"6","(-5525,1100)","0","mstr_standard","I14";
;
HDL_TAP"TRUE"
BODY_TYPE"PLUMBING"
CDS_LIB"mstr_standard";
"B \NAC \NWC"10;
"S \NAC"
BN"1"50;
%"TAP"
"6","(-2800,3650)","2","mstr_standard","I140";
;
HDL_TAP"TRUE"
BODY_TYPE"PLUMBING"
CDS_LIB"mstr_standard";
"B \NAC \NWC"3;
"S \NAC"
BN"16"120;
%"TAP"
"6","(-2800,3600)","2","mstr_standard","I141";
;
HDL_TAP"TRUE"
BODY_TYPE"PLUMBING"
CDS_LIB"mstr_standard";
"B \NAC \NWC"3;
"S \NAC"
BN"15"121;
%"TAP"
"6","(-2800,3550)","2","mstr_standard","I142";
;
HDL_TAP"TRUE"
BODY_TYPE"PLUMBING"
CDS_LIB"mstr_standard";
"B \NAC \NWC"3;
"S \NAC"
BN"14"122;
%"TAP"
"6","(-2800,3800)","2","mstr_standard","I143";
;
HDL_TAP"TRUE"
BODY_TYPE"PLUMBING"
CDS_LIB"mstr_standard";
"B \NAC \NWC"1;
"S \NAC"
BN"0"140;
%"TAP"
"6","(-2800,3900)","2","mstr_standard","I144";
;
HDL_TAP"TRUE"
BODY_TYPE"PLUMBING"
CDS_LIB"mstr_standard";
"B \NAC \NWC"1;
"S \NAC"
BN"2"16;
%"TAP"
"6","(-2800,3950)","2","mstr_standard","I145";
;
HDL_TAP"TRUE"
BODY_TYPE"PLUMBING"
CDS_LIB"mstr_standard";
"B \NAC \NWC"1;
"S \NAC"
BN"3"138;
%"TAP"
"6","(-2800,3850)","2","mstr_standard","I146";
;
HDL_TAP"TRUE"
BODY_TYPE"PLUMBING"
CDS_LIB"mstr_standard";
"B \NAC \NWC"1;
"S \NAC"
BN"1"139;
%"TAP"
"6","(-5525,1150)","0","mstr_standard","I15";
;
HDL_TAP"TRUE"
BODY_TYPE"PLUMBING"
CDS_LIB"mstr_standard";
"B \NAC \NWC"10;
"S \NAC"
BN"2"49;
%"TAP"
"6","(-2800,4150)","2","mstr_standard","I157";
;
HDL_TAP"TRUE"
BODY_TYPE"PLUMBING"
CDS_LIB"mstr_standard";
"B \NAC \NWC"1;
"S \NAC"
BN"7"169;
%"TAP"
"6","(-2800,4200)","2","mstr_standard","I158";
;
HDL_TAP"TRUE"
BODY_TYPE"PLUMBING"
CDS_LIB"mstr_standard";
"B \NAC \NWC"1;
"S \NAC"
BN"8"168;
%"TAP"
"6","(-2800,4050)","2","mstr_standard","I159";
;
HDL_TAP"TRUE"
BODY_TYPE"PLUMBING"
CDS_LIB"mstr_standard";
"B \NAC \NWC"1;
"S \NAC"
BN"5"136;
%"TAP"
"6","(-5525,1250)","0","mstr_standard","I16";
;
HDL_TAP"TRUE"
BODY_TYPE"PLUMBING"
CDS_LIB"mstr_standard";
"B \NAC \NWC"10;
"S \NAC"
BN"4"47;
%"TAP"
"6","(-2800,4100)","2","mstr_standard","I160";
;
HDL_TAP"TRUE"
BODY_TYPE"PLUMBING"
CDS_LIB"mstr_standard";
"B \NAC \NWC"1;
"S \NAC"
BN"6"170;
%"TAP"
"6","(-2800,4000)","2","mstr_standard","I161";
;
HDL_TAP"TRUE"
BODY_TYPE"PLUMBING"
CDS_LIB"mstr_standard";
"B \NAC \NWC"1;
"S \NAC"
BN"4"137;
%"TAP"
"6","(-2800,4450)","2","mstr_standard","I162";
;
HDL_TAP"TRUE"
BODY_TYPE"PLUMBING"
CDS_LIB"mstr_standard";
"B \NAC \NWC"1;
"S \NAC"
BN"13"163;
%"TAP"
"6","(-2800,4400)","2","mstr_standard","I163";
;
HDL_TAP"TRUE"
BODY_TYPE"PLUMBING"
CDS_LIB"mstr_standard";
"B \NAC \NWC"1;
"S \NAC"
BN"12"164;
%"TAP"
"6","(-2800,4350)","2","mstr_standard","I164";
;
HDL_TAP"TRUE"
BODY_TYPE"PLUMBING"
CDS_LIB"mstr_standard";
"B \NAC \NWC"1;
"S \NAC"
BN"11"165;
%"TAP"
"6","(-2800,4300)","2","mstr_standard","I165";
;
HDL_TAP"TRUE"
BODY_TYPE"PLUMBING"
CDS_LIB"mstr_standard";
"B \NAC \NWC"1;
"S \NAC"
BN"10"166;
%"TAP"
"6","(-2800,4250)","2","mstr_standard","I166";
;
HDL_TAP"TRUE"
BODY_TYPE"PLUMBING"
CDS_LIB"mstr_standard";
"B \NAC \NWC"1;
"S \NAC"
BN"9"167;
%"TAP"
"6","(-2800,4600)","2","mstr_standard","I167";
;
HDL_TAP"TRUE"
BODY_TYPE"PLUMBING"
CDS_LIB"mstr_standard";
"B \NAC \NWC"1;
"S \NAC"
BN"16"160;
%"TAP"
"6","(-2800,4650)","2","mstr_standard","I168";
;
HDL_TAP"TRUE"
BODY_TYPE"PLUMBING"
CDS_LIB"mstr_standard";
"B \NAC \NWC"1;
"S \NAC"
BN"17"159;
%"TAP"
"6","(-2800,4550)","2","mstr_standard","I169";
;
HDL_TAP"TRUE"
BODY_TYPE"PLUMBING"
CDS_LIB"mstr_standard";
"B \NAC \NWC"1;
"S \NAC"
BN"15"161;
%"TAP"
"6","(-5525,1200)","0","mstr_standard","I17";
;
HDL_TAP"TRUE"
BODY_TYPE"PLUMBING"
CDS_LIB"mstr_standard";
"B \NAC \NWC"10;
"S \NAC"
BN"3"48;
%"TAP"
"6","(-2800,4500)","2","mstr_standard","I170";
;
HDL_TAP"TRUE"
BODY_TYPE"PLUMBING"
CDS_LIB"mstr_standard";
"B \NAC \NWC"1;
"S \NAC"
BN"14"162;
%"SKX_EXT_B"
"4","(-4125,2550)","0","chpset_lib","I172";
;
CDS_SEC"4"
LOCATION"U5D1"
PART_NUMBER"TBD"
MATERIAL"IC"
PACK_TYPE"BGA1"
SEC_TYPE"BGA1"
CDS_LIB"chpset_lib"
SEC"4"
CDS_LOCATION"U5D1"
ROOM"CPU0";
"DDR1_PAR"
$PN"K53"156;
"DDR1_ODT<0>"
$PN"N50"118;
"DDR1_ODT<1>"
$PN"R48"117;
"DDR1_ODT<2>"
$PN"M49"116;
"DDR1_ODT<3>"
$PN"T47"19;
"DDR1_MA<0>"
$PN"J52"115;
"DDR1_MA<1>"
$PN"J58"114;
"DDR1_MA<2>"
$PN"K57"113;
"DDR1_MA<3>"
$PN"N58"155;
"DDR1_MA<4>"
$PN"M59"154;
"DDR1_MA<5>"
$PN"R58"153;
"DDR1_MA<6>"
$PN"T59"152;
"DDR1_MA<7>"
$PN"V61"151;
"DDR1_MA<8>"
$PN"W60"150;
"DDR1_MA<9>"
$PN"K59"149;
"DDR1_MA<10>"
$PN"M55"148;
"DDR1_MA<11>"
$PN"R60"147;
"DDR1_MA<12>"
$PN"T61"146;
"DDR1_MA<13>"
$PN"M51"145;
"DDR1_MA<14>"
$PN"T51"144;
"DDR1_MA<15>"
$PN"N52"143;
"DDR1_MA<16>"
$PN"R52"142;
"DDR1_MA<17>"
$PN"N48"141;
"DDR1_ECC<0>"
$PN"J70"51;
"DDR1_ECC<1>"
$PN"H69"50;
"DDR1_ECC<2>"
$PN"J66"49;
"DDR1_ECC<3>"
$PN"L66"48;
"DDR1_ECC<4>"
$PN"L70"47;
"DDR1_ECC<5>"
$PN"M69"46;
"DDR1_ECC<6>"
$PN"H67"45;
"DDR1_ECC<7>"
$PN"M67"44;
"DDR1_DQS_DP<0>"
$PN"AR80"140;
"DDR1_DQS_DP<1>"
$PN"AE80"139;
"DDR1_DQS_DP<2>"
$PN"H79"16;
"DDR1_DQS_DP<3>"
$PN"F73"138;
"DDR1_DQS_DP<4>"
$PN"R42"137;
"DDR1_DQS_DP<5>"
$PN"E34"136;
"DDR1_DQS_DP<6>"
$PN"E28"170;
"DDR1_DQS_DP<7>"
$PN"Y27"169;
"DDR1_DQS_DP<8>"
$PN"L68"168;
"DDR1_DQS_DP<9>"
$PN"AT81"167;
"DDR1_DQS_DP<10>"
$PN"AF81"166;
"DDR1_DQS_DP<11>"
$PN"F79"165;
"DDR1_DQS_DP<12>"
$PN"D73"164;
"DDR1_DQS_DP<13>"
$PN"L42"163;
"DDR1_DQS_DP<14>"
$PN"C34"162;
"DDR1_DQS_DP<15>"
$PN"C28"161;
"DDR1_DQS_DP<16>"
$PN"V27"160;
"DDR1_DQS_DP<17>"
$PN"J68"159;
"DDR1_DQS_DN<0>"
$PN"AP79"135;
"DDR1_DQS_DN<1>"
$PN"AD79"134;
"DDR1_DQS_DN<2>"
$PN"K79"133;
"DDR1_DQS_DN<3>"
$PN"H73"132;
"DDR1_DQS_DN<4>"
$PN"N42"131;
"DDR1_DQS_DN<5>"
$PN"G34"130;
"DDR1_DQS_DN<6>"
$PN"G28"129;
"DDR1_DQS_DN<7>"
$PN"AB27"128;
"DDR1_DQS_DN<8>"
$PN"N68"13;
"DDR1_DQS_DN<9>"
$PN"AU82"127;
"DDR1_DQS_DN<10>"
$PN"AG82"126;
"DDR1_DQS_DN<11>"
$PN"D79"125;
"DDR1_DQS_DN<12>"
$PN"B73"124;
"DDR1_DQS_DN<13>"
$PN"J42"123;
"DDR1_DQS_DN<14>"
$PN"A34"122;
"DDR1_DQS_DN<15>"
$PN"A28"121;
"DDR1_DQS_DN<16>"
$PN"T27"120;
"DDR1_DQS_DN<17>"
$PN"G68"119;
"DDR1_DQ<0>"
$PN"AV81"43;
"DDR1_DQ<1>"
$PN"AT79"42;
"DDR1_DQ<2>"
$PN"AN82"41;
"DDR1_DQ<3>"
$PN"AM81"40;
"DDR1_DQ<4>"
$PN"AW80"39;
"DDR1_DQ<5>"
$PN"AV79"24;
"DDR1_DQ<6>"
$PN"AR82"38;
"DDR1_DQ<7>"
$PN"AN80"37;
"DDR1_DQ<8>"
$PN"AH81"36;
"DDR1_DQ<9>"
$PN"AF79"35;
"DDR1_DQ<10>"
$PN"AC82"34;
"DDR1_DQ<11>"
$PN"AB81"86;
"DDR1_DQ<12>"
$PN"AJ80"85;
"DDR1_DQ<13>"
$PN"AH79"84;
"DDR1_DQ<14>"
$PN"AE82"83;
"DDR1_DQ<15>"
$PN"AC80"82;
"DDR1_DQ<16>"
$PN"E80"81;
"DDR1_DQ<17>"
$PN"J80"80;
"DDR1_DQ<18>"
$PN"F77"79;
"DDR1_DQ<19>"
$PN"H77"78;
"DDR1_DQ<20>"
$PN"F81"77;
"DDR1_DQ<21>"
$PN"H81"76;
"DDR1_DQ<22>"
$PN"E78"75;
"DDR1_DQ<23>"
$PN"J78"74;
"DDR1_DQ<24>"
$PN"D75"73;
"DDR1_DQ<25>"
$PN"C74"72;
"DDR1_DQ<26>"
$PN"D71"71;
"DDR1_DQ<27>"
$PN"F71"70;
"DDR1_DQ<28>"
$PN"F75"17;
"DDR1_DQ<29>"
$PN"G74"23;
"DDR1_DQ<30>"
$PN"C72"69;
"DDR1_DQ<31>"
$PN"G72"68;
"DDR1_DQ<32>"
$PN"K43"67;
"DDR1_DQ<33>"
$PN"H43"21;
"DDR1_DQ<34>"
$PN"L40"66;
"DDR1_DQ<35>"
$PN"N40"20;
"DDR1_DQ<36>"
$PN"P43"65;
"DDR1_DQ<37>"
$PN"T43"64;
"DDR1_DQ<38>"
$PN"K41"22;
"DDR1_DQ<39>"
$PN"P41"63;
"DDR1_DQ<40>"
$PN"C36"62;
"DDR1_DQ<41>"
$PN"B35"15;
"DDR1_DQ<42>"
$PN"C32"61;
"DDR1_DQ<43>"
$PN"E32"60;
"DDR1_DQ<44>"
$PN"E36"59;
"DDR1_DQ<45>"
$PN"F35"58;
"DDR1_DQ<46>"
$PN"B33"57;
"DDR1_DQ<47>"
$PN"F33"56;
"DDR1_DQ<48>"
$PN"C30"55;
"DDR1_DQ<49>"
$PN"B29"54;
"DDR1_DQ<50>"
$PN"C26"53;
"DDR1_DQ<51>"
$PN"E26"52;
"DDR1_DQ<52>"
$PN"E30"96;
"DDR1_DQ<53>"
$PN"F29"18;
"DDR1_DQ<54>"
$PN"B27"95;
"DDR1_DQ<55>"
$PN"F27"14;
"DDR1_DQ<56>"
$PN"U28"94;
"DDR1_DQ<57>"
$PN"AA28"93;
"DDR1_DQ<58>"
$PN"V25"92;
"DDR1_DQ<59>"
$PN"Y25"91;
"DDR1_DQ<60>"
$PN"V29"90;
"DDR1_DQ<61>"
$PN"Y29"89;
"DDR1_DQ<62>"
$PN"U26"88;
"DDR1_DQ<63>"
$PN"AA26"87;
"DDR1_CS_N<0>"
$PN"K51"112;
"DDR1_CS_N<1>"
$PN"R50"111;
"DDR1_CS_N<2>"
$PN"N46"110;
"DDR1_CS_N<3>"
$PN"V47"109;
"DDR1_CS_N<4>"
$PN"J50"108;
"DDR1_CS_N<5>"
$PN"T49"107;
"DDR1_CS_N<6>"
$PN"M45"106;
"DDR1_CS_N<7>"
$PN"R46"105;
"DDR1_CLK_DP<0>"
$PN"N54"33;
"DDR1_CLK_DP<1>"
$PN"T55"32;
"DDR1_CLK_DP<2>"
$PN"M57"31;
"DDR1_CLK_DP<3>"
$PN"T57"30;
"DDR1_CLK_DN<0>"
$PN"M53"29;
"DDR1_CLK_DN<1>"
$PN"R54"28;
"DDR1_CLK_DN<2>"
$PN"N56"27;
"DDR1_CLK_DN<3>"
$PN"R56"26;
"DDR1_CKE<0>"
$PN"N62"104;
"DDR1_CKE<1>"
$PN"R64"103;
"DDR1_CKE<2>"
$PN"K63"102;
"DDR1_CKE<3>"
$PN"L64"101;
"DDR1_CID<2>"
$PN"M47"25;
"DDR1_BG<0>"
$PN"M61"100;
"DDR1_BG<1>"
$PN"N60"99;
"DDR1_BA<0>"
$PN"T53"98;
"DDR1_BA<1>"
$PN"K55"97;
"DDR1_ALERT_N"
$PN"W62"157;
"DDR1_ACT_N"
$PN"T63"158;
%"TAP"
"6","(-5525,1300)","0","mstr_standard","I18";
;
HDL_TAP"TRUE"
BODY_TYPE"PLUMBING"
CDS_LIB"mstr_standard";
"B \NAC \NWC"10;
"S \NAC"
BN"5"46;
%"TAP"
"6","(-5525,1350)","0","mstr_standard","I19";
;
HDL_TAP"TRUE"
BODY_TYPE"PLUMBING"
CDS_LIB"mstr_standard";
"B \NAC \NWC"10;
"S \NAC"
BN"6"45;
%"TAP"
"6","(-5525,1400)","0","mstr_standard","I20";
;
HDL_TAP"TRUE"
BODY_TYPE"PLUMBING"
CDS_LIB"mstr_standard";
"B \NAC \NWC"10;
"S \NAC"
BN"7"44;
%"TAP"
"6","(-5525,1500)","0","mstr_standard","I21";
;
HDL_TAP"TRUE"
BODY_TYPE"PLUMBING"
CDS_LIB"mstr_standard";
"B \NAC \NWC"9;
"S \NAC"
BN"0"43;
%"TAP"
"6","(-5525,1550)","0","mstr_standard","I22";
;
HDL_TAP"TRUE"
BODY_TYPE"PLUMBING"
CDS_LIB"mstr_standard";
"B \NAC \NWC"9;
"S \NAC"
BN"1"42;
%"TAP"
"6","(-5525,1600)","0","mstr_standard","I23";
;
HDL_TAP"TRUE"
BODY_TYPE"PLUMBING"
CDS_LIB"mstr_standard";
"B \NAC \NWC"9;
"S \NAC"
BN"2"41;
%"TAP"
"6","(-5525,1650)","0","mstr_standard","I24";
;
HDL_TAP"TRUE"
BODY_TYPE"PLUMBING"
CDS_LIB"mstr_standard";
"B \NAC \NWC"9;
"S \NAC"
BN"3"40;
%"TAP"
"6","(-5525,1700)","0","mstr_standard","I25";
;
HDL_TAP"TRUE"
BODY_TYPE"PLUMBING"
CDS_LIB"mstr_standard";
"B \NAC \NWC"9;
"S \NAC"
BN"4"39;
%"TAP"
"6","(-5525,1750)","0","mstr_standard","I26";
;
HDL_TAP"TRUE"
BODY_TYPE"PLUMBING"
CDS_LIB"mstr_standard";
"B \NAC \NWC"9;
"S \NAC"
BN"5"24;
%"TAP"
"6","(-5525,1800)","0","mstr_standard","I27";
;
HDL_TAP"TRUE"
BODY_TYPE"PLUMBING"
CDS_LIB"mstr_standard";
"B \NAC \NWC"9;
"S \NAC"
BN"6"38;
%"TAP"
"6","(-5525,1850)","0","mstr_standard","I28";
;
HDL_TAP"TRUE"
BODY_TYPE"PLUMBING"
CDS_LIB"mstr_standard";
"B \NAC \NWC"9;
"S \NAC"
BN"7"37;
%"TAP"
"6","(-5525,1900)","0","mstr_standard","I29";
;
HDL_TAP"TRUE"
BODY_TYPE"PLUMBING"
CDS_LIB"mstr_standard";
"B \NAC \NWC"9;
"S \NAC"
BN"8"36;
%"TAP"
"6","(-5525,2000)","0","mstr_standard","I31";
;
HDL_TAP"TRUE"
BODY_TYPE"PLUMBING"
CDS_LIB"mstr_standard";
"B \NAC \NWC"9;
"S \NAC"
BN"10"34;
%"TAP"
"6","(-5525,1950)","0","mstr_standard","I32";
;
HDL_TAP"TRUE"
BODY_TYPE"PLUMBING"
CDS_LIB"mstr_standard";
"B \NAC \NWC"9;
"S \NAC"
BN"9"35;
%"TAP"
"6","(-5525,2100)","0","mstr_standard","I33";
;
HDL_TAP"TRUE"
BODY_TYPE"PLUMBING"
CDS_LIB"mstr_standard";
"B \NAC \NWC"9;
"S \NAC"
BN"12"85;
%"TAP"
"6","(-5525,2150)","0","mstr_standard","I34";
;
HDL_TAP"TRUE"
BODY_TYPE"PLUMBING"
CDS_LIB"mstr_standard";
"B \NAC \NWC"9;
"S \NAC"
BN"13"84;
%"TAP"
"6","(-5525,2050)","0","mstr_standard","I35";
;
HDL_TAP"TRUE"
BODY_TYPE"PLUMBING"
CDS_LIB"mstr_standard";
"B \NAC \NWC"9;
"S \NAC"
BN"11"86;
%"TAP"
"6","(-5525,2200)","0","mstr_standard","I36";
;
HDL_TAP"TRUE"
BODY_TYPE"PLUMBING"
CDS_LIB"mstr_standard";
"B \NAC \NWC"9;
"S \NAC"
BN"14"83;
%"TAP"
"6","(-5525,2250)","0","mstr_standard","I37";
;
HDL_TAP"TRUE"
BODY_TYPE"PLUMBING"
CDS_LIB"mstr_standard";
"B \NAC \NWC"9;
"S \NAC"
BN"15"82;
%"TAP"
"6","(-5525,2300)","0","mstr_standard","I38";
;
HDL_TAP"TRUE"
BODY_TYPE"PLUMBING"
CDS_LIB"mstr_standard";
"B \NAC \NWC"9;
"S \NAC"
BN"16"81;
%"TAP"
"6","(-5525,2350)","0","mstr_standard","I39";
;
HDL_TAP"TRUE"
BODY_TYPE"PLUMBING"
CDS_LIB"mstr_standard";
"B \NAC \NWC"9;
"S \NAC"
BN"17"80;
%"TAP"
"6","(-5525,2400)","0","mstr_standard","I40";
;
HDL_TAP"TRUE"
BODY_TYPE"PLUMBING"
CDS_LIB"mstr_standard";
"B \NAC \NWC"9;
"S \NAC"
BN"18"79;
%"TAP"
"6","(-5525,2500)","0","mstr_standard","I41";
;
HDL_TAP"TRUE"
BODY_TYPE"PLUMBING"
CDS_LIB"mstr_standard";
"B \NAC \NWC"9;
"S \NAC"
BN"20"77;
%"TAP"
"6","(-5525,2450)","0","mstr_standard","I42";
;
HDL_TAP"TRUE"
BODY_TYPE"PLUMBING"
CDS_LIB"mstr_standard";
"B \NAC \NWC"9;
"S \NAC"
BN"19"78;
%"TAP"
"6","(-5525,2550)","0","mstr_standard","I43";
;
HDL_TAP"TRUE"
BODY_TYPE"PLUMBING"
CDS_LIB"mstr_standard";
"B \NAC \NWC"9;
"S \NAC"
BN"21"76;
%"TAP"
"6","(-5525,2600)","0","mstr_standard","I44";
;
HDL_TAP"TRUE"
BODY_TYPE"PLUMBING"
CDS_LIB"mstr_standard";
"B \NAC \NWC"9;
"S \NAC"
BN"22"75;
%"TAP"
"6","(-5525,2650)","0","mstr_standard","I45";
;
HDL_TAP"TRUE"
BODY_TYPE"PLUMBING"
CDS_LIB"mstr_standard";
"B \NAC \NWC"9;
"S \NAC"
BN"23"74;
%"TAP"
"6","(-5525,2700)","0","mstr_standard","I46";
;
HDL_TAP"TRUE"
BODY_TYPE"PLUMBING"
CDS_LIB"mstr_standard";
"B \NAC \NWC"9;
"S \NAC"
BN"24"73;
%"TAP"
"6","(-5525,2750)","0","mstr_standard","I47";
;
HDL_TAP"TRUE"
BODY_TYPE"PLUMBING"
CDS_LIB"mstr_standard";
"B \NAC \NWC"9;
"S \NAC"
BN"25"72;
%"TAP"
"6","(-5525,2800)","0","mstr_standard","I48";
;
HDL_TAP"TRUE"
BODY_TYPE"PLUMBING"
CDS_LIB"mstr_standard";
"B \NAC \NWC"9;
"S \NAC"
BN"26"71;
%"TAP"
"6","(-5525,2850)","0","mstr_standard","I49";
;
HDL_TAP"TRUE"
BODY_TYPE"PLUMBING"
CDS_LIB"mstr_standard";
"B \NAC \NWC"9;
"S \NAC"
BN"27"70;
%"TAP"
"6","(-5525,600)","0","mstr_standard","I5";
;
HDL_TAP"TRUE"
BODY_TYPE"PLUMBING"
CDS_LIB"mstr_standard";
"B \NAC \NWC"12;
"S \NAC"
BN"0"29;
%"TAP"
"6","(-5525,2900)","0","mstr_standard","I50";
;
HDL_TAP"TRUE"
BODY_TYPE"PLUMBING"
CDS_LIB"mstr_standard";
"B \NAC \NWC"9;
"S \NAC"
BN"28"17;
%"TAP"
"6","(-5525,3000)","0","mstr_standard","I51";
;
HDL_TAP"TRUE"
BODY_TYPE"PLUMBING"
CDS_LIB"mstr_standard";
"B \NAC \NWC"9;
"S \NAC"
BN"30"69;
%"TAP"
"6","(-5525,2950)","0","mstr_standard","I52";
;
HDL_TAP"TRUE"
BODY_TYPE"PLUMBING"
CDS_LIB"mstr_standard";
"B \NAC \NWC"9;
"S \NAC"
BN"29"23;
%"TAP"
"6","(-5525,3050)","0","mstr_standard","I53";
;
HDL_TAP"TRUE"
BODY_TYPE"PLUMBING"
CDS_LIB"mstr_standard";
"B \NAC \NWC"9;
"S \NAC"
BN"31"68;
%"TAP"
"6","(-5525,3100)","0","mstr_standard","I54";
;
HDL_TAP"TRUE"
BODY_TYPE"PLUMBING"
CDS_LIB"mstr_standard";
"B \NAC \NWC"9;
"S \NAC"
BN"32"67;
%"TAP"
"6","(-5525,3150)","0","mstr_standard","I55";
;
HDL_TAP"TRUE"
BODY_TYPE"PLUMBING"
CDS_LIB"mstr_standard";
"B \NAC \NWC"9;
"S \NAC"
BN"33"21;
%"TAP"
"6","(-5525,3200)","0","mstr_standard","I56";
;
HDL_TAP"TRUE"
BODY_TYPE"PLUMBING"
CDS_LIB"mstr_standard";
"B \NAC \NWC"9;
"S \NAC"
BN"34"66;
%"TAP"
"6","(-5525,3300)","0","mstr_standard","I57";
;
HDL_TAP"TRUE"
BODY_TYPE"PLUMBING"
CDS_LIB"mstr_standard";
"B \NAC \NWC"9;
"S \NAC"
BN"36"65;
%"TAP"
"6","(-5525,3250)","0","mstr_standard","I58";
;
HDL_TAP"TRUE"
BODY_TYPE"PLUMBING"
CDS_LIB"mstr_standard";
"B \NAC \NWC"9;
"S \NAC"
BN"35"20;
%"TAP"
"6","(-5525,3350)","0","mstr_standard","I59";
;
HDL_TAP"TRUE"
BODY_TYPE"PLUMBING"
CDS_LIB"mstr_standard";
"B \NAC \NWC"9;
"S \NAC"
BN"37"64;
%"TAP"
"6","(-5525,650)","0","mstr_standard","I6";
;
HDL_TAP"TRUE"
BODY_TYPE"PLUMBING"
CDS_LIB"mstr_standard";
"B \NAC \NWC"12;
"S \NAC"
BN"1"28;
%"TAP"
"6","(-5525,3400)","0","mstr_standard","I60";
;
HDL_TAP"TRUE"
BODY_TYPE"PLUMBING"
CDS_LIB"mstr_standard";
"B \NAC \NWC"9;
"S \NAC"
BN"38"22;
%"TAP"
"6","(-5525,3450)","0","mstr_standard","I61";
;
HDL_TAP"TRUE"
BODY_TYPE"PLUMBING"
CDS_LIB"mstr_standard";
"B \NAC \NWC"9;
"S \NAC"
BN"39"63;
%"TAP"
"6","(-5525,3550)","0","mstr_standard","I62";
;
HDL_TAP"TRUE"
BODY_TYPE"PLUMBING"
CDS_LIB"mstr_standard";
"B \NAC \NWC"9;
"S \NAC"
BN"41"15;
%"TAP"
"6","(-5525,3500)","0","mstr_standard","I63";
;
HDL_TAP"TRUE"
BODY_TYPE"PLUMBING"
CDS_LIB"mstr_standard";
"B \NAC \NWC"9;
"S \NAC"
BN"40"62;
%"TAP"
"6","(-5525,3600)","0","mstr_standard","I64";
;
HDL_TAP"TRUE"
BODY_TYPE"PLUMBING"
CDS_LIB"mstr_standard";
"B \NAC \NWC"9;
"S \NAC"
BN"42"61;
%"TAP"
"6","(-5525,3650)","0","mstr_standard","I65";
;
HDL_TAP"TRUE"
BODY_TYPE"PLUMBING"
CDS_LIB"mstr_standard";
"B \NAC \NWC"9;
"S \NAC"
BN"43"60;
%"TAP"
"6","(-5525,3700)","0","mstr_standard","I66";
;
HDL_TAP"TRUE"
BODY_TYPE"PLUMBING"
CDS_LIB"mstr_standard";
"B \NAC \NWC"9;
"S \NAC"
BN"44"59;
%"TAP"
"6","(-5525,3750)","0","mstr_standard","I67";
;
HDL_TAP"TRUE"
BODY_TYPE"PLUMBING"
CDS_LIB"mstr_standard";
"B \NAC \NWC"9;
"S \NAC"
BN"45"58;
%"TAP"
"6","(-5525,3800)","0","mstr_standard","I68";
;
HDL_TAP"TRUE"
BODY_TYPE"PLUMBING"
CDS_LIB"mstr_standard";
"B \NAC \NWC"9;
"S \NAC"
BN"46"57;
%"TAP"
"6","(-5525,3850)","0","mstr_standard","I69";
;
HDL_TAP"TRUE"
BODY_TYPE"PLUMBING"
CDS_LIB"mstr_standard";
"B \NAC \NWC"9;
"S \NAC"
BN"47"56;
%"TAP"
"6","(-5525,700)","0","mstr_standard","I7";
;
HDL_TAP"TRUE"
BODY_TYPE"PLUMBING"
CDS_LIB"mstr_standard";
"B \NAC \NWC"12;
"S \NAC"
BN"2"27;
%"TAP"
"6","(-5525,3900)","0","mstr_standard","I70";
;
HDL_TAP"TRUE"
BODY_TYPE"PLUMBING"
CDS_LIB"mstr_standard";
"B \NAC \NWC"9;
"S \NAC"
BN"48"55;
%"TAP"
"6","(-5525,3950)","0","mstr_standard","I71";
;
HDL_TAP"TRUE"
BODY_TYPE"PLUMBING"
CDS_LIB"mstr_standard";
"B \NAC \NWC"9;
"S \NAC"
BN"49"54;
%"TAP"
"6","(-5525,4050)","0","mstr_standard","I73";
;
HDL_TAP"TRUE"
BODY_TYPE"PLUMBING"
CDS_LIB"mstr_standard";
"B \NAC \NWC"9;
"S \NAC"
BN"51"52;
%"TAP"
"6","(-5525,4000)","0","mstr_standard","I74";
;
HDL_TAP"TRUE"
BODY_TYPE"PLUMBING"
CDS_LIB"mstr_standard";
"B \NAC \NWC"9;
"S \NAC"
BN"50"53;
%"TAP"
"6","(-5525,4150)","0","mstr_standard","I75";
;
HDL_TAP"TRUE"
BODY_TYPE"PLUMBING"
CDS_LIB"mstr_standard";
"B \NAC \NWC"9;
"S \NAC"
BN"53"18;
%"TAP"
"6","(-5525,4200)","0","mstr_standard","I76";
;
HDL_TAP"TRUE"
BODY_TYPE"PLUMBING"
CDS_LIB"mstr_standard";
"B \NAC \NWC"9;
"S \NAC"
BN"54"95;
%"TAP"
"6","(-5525,4100)","0","mstr_standard","I77";
;
HDL_TAP"TRUE"
BODY_TYPE"PLUMBING"
CDS_LIB"mstr_standard";
"B \NAC \NWC"9;
"S \NAC"
BN"52"96;
%"TAP"
"6","(-5525,4250)","0","mstr_standard","I78";
;
HDL_TAP"TRUE"
BODY_TYPE"PLUMBING"
CDS_LIB"mstr_standard";
"B \NAC \NWC"9;
"S \NAC"
BN"55"14;
%"TAP"
"6","(-5525,4300)","0","mstr_standard","I79";
;
HDL_TAP"TRUE"
BODY_TYPE"PLUMBING"
CDS_LIB"mstr_standard";
"B \NAC \NWC"9;
"S \NAC"
BN"56"94;
%"TAP"
"6","(-5525,800)","0","mstr_standard","I8";
;
HDL_TAP"TRUE"
BODY_TYPE"PLUMBING"
CDS_LIB"mstr_standard";
"B \NAC \NWC"11;
"S \NAC"
BN"0"33;
%"TAP"
"6","(-5525,4350)","0","mstr_standard","I80";
;
HDL_TAP"TRUE"
BODY_TYPE"PLUMBING"
CDS_LIB"mstr_standard";
"B \NAC \NWC"9;
"S \NAC"
BN"57"93;
%"TAP"
"6","(-5525,4400)","0","mstr_standard","I81";
;
HDL_TAP"TRUE"
BODY_TYPE"PLUMBING"
CDS_LIB"mstr_standard";
"B \NAC \NWC"9;
"S \NAC"
BN"58"92;
%"TAP"
"6","(-5525,4450)","0","mstr_standard","I82";
;
HDL_TAP"TRUE"
BODY_TYPE"PLUMBING"
CDS_LIB"mstr_standard";
"B \NAC \NWC"9;
"S \NAC"
BN"59"91;
%"TAP"
"6","(-5525,4500)","0","mstr_standard","I83";
;
HDL_TAP"TRUE"
BODY_TYPE"PLUMBING"
CDS_LIB"mstr_standard";
"B \NAC \NWC"9;
"S \NAC"
BN"60"90;
%"TAP"
"6","(-5525,4550)","0","mstr_standard","I84";
;
HDL_TAP"TRUE"
BODY_TYPE"PLUMBING"
CDS_LIB"mstr_standard";
"B \NAC \NWC"9;
"S \NAC"
BN"61"89;
%"TAP"
"6","(-5525,4650)","0","mstr_standard","I85";
;
HDL_TAP"TRUE"
BODY_TYPE"PLUMBING"
CDS_LIB"mstr_standard";
"B \NAC \NWC"9;
"S \NAC"
BN"63"87;
%"TAP"
"6","(-5525,4600)","0","mstr_standard","I86";
;
HDL_TAP"TRUE"
BODY_TYPE"PLUMBING"
CDS_LIB"mstr_standard";
"B \NAC \NWC"9;
"S \NAC"
BN"62"88;
%"TAP"
"6","(-2800,800)","2","mstr_standard","I87";
;
HDL_TAP"TRUE"
BODY_TYPE"PLUMBING"
CDS_LIB"mstr_standard";
"B \NAC \NWC"7;
"S \NAC"
BN"0"100;
%"TAP"
"6","(-2800,850)","2","mstr_standard","I88";
;
HDL_TAP"TRUE"
BODY_TYPE"PLUMBING"
CDS_LIB"mstr_standard";
"B \NAC \NWC"7;
"S \NAC"
BN"1"99;
%"TAP"
"6","(-2800,750)","2","mstr_standard","I89";
;
HDL_TAP"TRUE"
BODY_TYPE"PLUMBING"
CDS_LIB"mstr_standard";
"B \NAC \NWC"8;
"S \NAC"
BN"1"97;
%"TAP"
"6","(-5525,850)","0","mstr_standard","I9";
;
HDL_TAP"TRUE"
BODY_TYPE"PLUMBING"
CDS_LIB"mstr_standard";
"B \NAC \NWC"11;
"S \NAC"
BN"1"32;
%"TAP"
"6","(-2800,700)","2","mstr_standard","I90";
;
HDL_TAP"TRUE"
BODY_TYPE"PLUMBING"
CDS_LIB"mstr_standard";
"B \NAC \NWC"8;
"S \NAC"
BN"0"98;
%"TAP"
"6","(-2800,950)","2","mstr_standard","I91";
;
HDL_TAP"TRUE"
BODY_TYPE"PLUMBING"
CDS_LIB"mstr_standard";
"B \NAC \NWC"5;
"S \NAC"
BN"0"112;
%"TAP"
"6","(-2800,1150)","2","mstr_standard","I92";
;
HDL_TAP"TRUE"
BODY_TYPE"PLUMBING"
CDS_LIB"mstr_standard";
"B \NAC \NWC"5;
"S \NAC"
BN"4"108;
%"TAP"
"6","(-2800,1100)","2","mstr_standard","I93";
;
HDL_TAP"TRUE"
BODY_TYPE"PLUMBING"
CDS_LIB"mstr_standard";
"B \NAC \NWC"5;
"S \NAC"
BN"3"109;
%"TAP"
"6","(-2800,1050)","2","mstr_standard","I94";
;
HDL_TAP"TRUE"
BODY_TYPE"PLUMBING"
CDS_LIB"mstr_standard";
"B \NAC \NWC"5;
"S \NAC"
BN"2"110;
%"TAP"
"6","(-2800,1000)","2","mstr_standard","I95";
;
HDL_TAP"TRUE"
BODY_TYPE"PLUMBING"
CDS_LIB"mstr_standard";
"B \NAC \NWC"5;
"S \NAC"
BN"1"111;
%"TAP"
"6","(-2800,1400)","2","mstr_standard","I96";
;
HDL_TAP"TRUE"
BODY_TYPE"PLUMBING"
CDS_LIB"mstr_standard";
"B \NAC \NWC"4;
"S \NAC"
BN"0"118;
%"TAP"
"6","(-2800,1250)","2","mstr_standard","I97";
;
HDL_TAP"TRUE"
BODY_TYPE"PLUMBING"
CDS_LIB"mstr_standard";
"B \NAC \NWC"5;
"S \NAC"
BN"6"106;
%"TAP"
"6","(-2800,1200)","2","mstr_standard","I98";
;
HDL_TAP"TRUE"
BODY_TYPE"PLUMBING"
CDS_LIB"mstr_standard";
"B \NAC \NWC"5;
"S \NAC"
BN"5"107;
%"TAP"
"6","(-2800,1300)","2","mstr_standard","I99";
;
HDL_TAP"TRUE"
BODY_TYPE"PLUMBING"
CDS_LIB"mstr_standard";
"B \NAC \NWC"5;
"S \NAC"
BN"7"105;
END.
